# BASEBOARD_FAB2 (Tioga Pass) — schematic parts with pin connectivity, parts 2400–2400 of 4751; source: Cadence DE-HDL packaged netlist (pstxprt.dat, pstxnet.dat, pstchip.dat)

J9L2  SCONN288_H44441003  SCONN  pkg PIP  page 86
  1  \12v\(1)  = P12V_NVDIMM_KLM
  2  VSS(93)  GROUND  = GND
  3  DQ(4)  BI  = M_L_DQ<4>
  4  VSS(92)  GROUND  = GND
  5  DQ(0)  BI  = M_L_DQ<0>
  6  VSS(91)  GROUND  = GND
  7  DQS9P  BI  = M_L_DQS_DP<9>
  8  DQS9N  BI  = M_L_DQS_DN<9>
  9  VSS(90)  GROUND  = GND
  10  DQ(6)  BI  = M_L_DQ<6>
  11  VSS(89)  GROUND  = GND
  12  DQ(2)  BI  = M_L_DQ<2>
  13  VSS(88)  GROUND  = GND
  14  DQ(12)  BI  = M_L_DQ<12>
  15  VSS(87)  GROUND  = GND
  16  DQ(8)  BI  = M_L_DQ<8>
  17  VSS(86)  GROUND  = GND
  18  DQS10P  BI  = M_L_DQS_DP<10>
  19  DQS10N  BI  = M_L_DQS_DN<10>
  20  VSS(85)  GROUND  = GND
  21  DQ(14)  BI  = M_L_DQ<14>
  22  VSS(84)  GROUND  = GND
  23  DQ(10)  BI  = M_L_DQ<10>
  24  VSS(83)  GROUND  = GND
  25  DQ(20)  BI  = M_L_DQ<20>
  26  VSS(82)  GROUND  = GND
  27  DQ(16)  BI  = M_L_DQ<16>
  28  VSS(81)  GROUND  = GND
  29  DQS11P  BI  = M_L_DQS_DP<11>
  30  DQS11N  BI  = M_L_DQS_DN<11>
  31  VSS(80)  GROUND  = GND
  32  DQ(22)  BI  = M_L_DQ<22>
  33  VSS(79)  GROUND  = GND
  34  DQ(18)  BI  = M_L_DQ<18>
  35  VSS(78)  GROUND  = GND
  36  DQ(28)  BI  = M_L_DQ<28>
  37  VSS(77)  GROUND  = GND
  38  DQ(24)  BI  = M_L_DQ<24>
  39  VSS(76)  GROUND  = GND
  40  DQS12P  BI  = M_L_DQS_DP<12>
  41  DQS12N  BI  = M_L_DQS_DN<12>
  42  VSS(75)  GROUND  = GND
  43  DQ(30)  BI  = M_L_DQ<30>
  44  VSS(74)  GROUND  = GND
  45  DQ(26)  BI  = M_L_DQ<26>
  46  VSS(73)  GROUND  = GND
  47  CB(4)  BI  = M_L_ECC<4>
  48  VSS(72)  GROUND  = GND
  49  CB(0)  BI  = M_L_ECC<0>
  50  VSS(71)  GROUND  = GND
  51  DQS17P  BI  = M_L_DQS_DP<17>
  52  DQS17N  BI  = M_L_DQS_DN<17>
  53  VSS(70)  GROUND  = GND
  54  CB(6)  BI  = M_L_ECC<6>
  55  VSS(69)  GROUND  = GND
  56  CB(2)  BI  = M_L_ECC<2>
  57  VSS(68)  GROUND  = GND
  58  RESET_N  BI  = M_KLM_RST_N
  59  VDD(25)  POWER  = PVDDQ_KLM
  60  CKE(0)  BI  = M_L_CKE<2>
  61  VDD(24)  POWER  = PVDDQ_KLM
  62  ACT_N  BI  = M_L_ACT_N
  63  BG(0)  BI  = M_L_BG<0>
  64  VDD(23)  POWER  = PVDDQ_KLM
  65  A12  BI  = M_L_MA<12>
  66  A9  BI  = M_L_MA<9>
  67  VDD(22)  POWER  = PVDDQ_KLM
  68  A8  BI  = M_L_MA<8>
  69  A6  BI  = M_L_MA<6>
  70  VDD(21)  POWER  = PVDDQ_KLM
  71  A3  BI  = M_L_MA<3>
  72  A1  BI  = M_L_MA<1>
  73  VDD(20)  POWER  = PVDDQ_KLM
  74  CK0P  BI  = M_L_CLK_DP<2>
  75  CK0N  BI  = M_L_CLK_DN<2>
  76  VDD(19)  POWER  = PVDDQ_KLM
  77  VTT(1)  POWER  = PVTT_KLM
  78  EVENT_N  BI  = FM_DIMM_EVENT_COD_N
  79  A0  BI  = M_L_MA<0>
  80  VDD(18)  POWER  = PVDDQ_KLM
  81  BA(0)  BI  = M_L_BA<0>
  82  A16_RAS_N  BI  = M_L_MA<16>
  83  VDD(17)  POWER  = PVDDQ_KLM
  84  S0_N  BI  = M_L_CS_N<4>
  85  VDD(16)  POWER  = PVDDQ_KLM
  86  A15_CAS_N  BI  = M_L_MA<15>
  87  ODT(0)  BI  = M_L_ODT<2>
  88  VDD(15)  POWER  = PVDDQ_KLM
  89  S1_N  BI  = M_L_CS_N<5>
  90  VDD(14)  POWER  = PVDDQ_KLM
  91  ODT(1)  BI  = M_L_ODT<3>
  92  VDD(13)  POWER  = PVDDQ_KLM
  93  S2_N_C(0)  BI  = M_L_CS_N<6>
  94  VSS(67)  GROUND  = GND
  95  DQ(36)  BI  = M_L_DQ<36>
  96  VSS(66)  GROUND  = GND
  97  DQ(32)  BI  = M_L_DQ<32>
  98  VSS(65)  GROUND  = GND
  99  DQS13P  BI  = M_L_DQS_DP<13>
  100  DQS13N  BI  = M_L_DQS_DN<13>
  101  VSS(64)  GROUND  = GND
  102  DQ(38)  BI  = M_L_DQ<38>
  103  VSS(63)  GROUND  = GND
  104  DQ(34)  BI  = M_L_DQ<34>
  105  VSS(62)  GROUND  = GND
  106  DQ(44)  BI  = M_L_DQ<44>
  107  VSS(61)  GROUND  = GND
  108  DQ(40)  BI  = M_L_DQ<40>
  109  VSS(60)  GROUND  = GND
  110  DQS14P  BI  = M_L_DQS_DP<14>
  111  DQS14N  BI  = M_L_DQS_DN<14>
  112  VSS(59)  GROUND  = GND
  113  DQ(46)  BI  = M_L_DQ<46>
  114  VSS(58)  GROUND  = GND
  115  DQ(42)  BI  = M_L_DQ<42>
  116  VSS(57)  GROUND  = GND
  117  DQ(52)  BI  = M_L_DQ<52>
  118  VSS(56)  GROUND  = GND
  119  DQ(48)  BI  = M_L_DQ<48>
  120  VSS(55)  GROUND  = GND
  121  DQS15P  BI  = M_L_DQS_DP<15>
  122  DQS15N  BI  = M_L_DQS_DN<15>
  123  VSS(54)  GROUND  = GND
  124  DQ(54)  BI  = M_L_DQ<54>
  125  VSS(53)  GROUND  = GND
  126  DQ(50)  BI  = M_L_DQ<50>
  127  VSS(52)  GROUND  = GND
  128  DQ(60)  BI  = M_L_DQ<60>
  129  VSS(51)  GROUND  = GND
  130  DQ(56)  BI  = M_L_DQ<56>
  131  VSS(50)  GROUND  = GND
  132  DQS16P  BI  = M_L_DQS_DP<16>
  133  DQS16N  BI  = M_L_DQS_DN<16>
  134  VSS(49)  GROUND  = GND
  135  DQ(62)  BI  = M_L_DQ<62>
  136  VSS(48)  GROUND  = GND
  137  DQ(58)  BI  = M_L_DQ<58>
  138  VSS(47)  GROUND  = GND
  139  SA(0)  BI  = PVPP_KLM
  140  SA(1)  BI  = PVPP_KLM
  141  SCL  BI  = SMB_DDR_KLM_VPP_SCL
  142  VPP(4)  POWER  = PVPP_KLM
  143  VPP(3)  POWER  = PVPP_KLM
  144  RFU(2)  BI  = TP_CH_L_DIMM0_RFU_2
  145  \12v\(0)  = P12V_NVDIMM_KLM
  146  VREFCA  BI  = M_L_VREF
  147  VSS(46)  GROUND  = GND
  148  DQ(5)  BI  = M_L_DQ<5>
  149  VSS(45)  GROUND  = GND
  150  DQ(1)  BI  = M_L_DQ<1>
  151  VSS(44)  GROUND  = GND
  152  DQS0N  BI  = M_L_DQS_DN<0>
  153  DQS0P  BI  = M_L_DQS_DP<0>
  154  VSS(43)  GROUND  = GND
  155  DQ(7)  BI  = M_L_DQ<7>
  156  VSS(42)  GROUND  = GND
  157  DQ(3)  BI  = M_L_DQ<3>
  158  VSS(41)  GROUND  = GND
  159  DQ(13)  BI  = M_L_DQ<13>
  160  VSS(40)  GROUND  = GND
  161  DQ(9)  BI  = M_L_DQ<9>
  162  VSS(39)  GROUND  = GND
  163  DQS1N  BI  = M_L_DQS_DN<1>
  164  DQS1P  BI  = M_L_DQS_DP<1>
  165  VSS(38)  GROUND  = GND
  166  DQ(15)  BI  = M_L_DQ<15>
  167  VSS(37)  GROUND  = GND
  168  DQ(11)  BI  = M_L_DQ<11>
  169  VSS(36)  GROUND  = GND
  170  DQ(21)  BI  = M_L_DQ<21>
  171  VSS(35)  GROUND  = GND
  172  DQ(17)  BI  = M_L_DQ<17>
  173  VSS(34)  GROUND  = GND
  174  DQS2N  BI  = M_L_DQS_DN<2>
  175  DQS2P  BI  = M_L_DQS_DP<2>
  176  VSS(33)  GROUND  = GND
  177  DQ(23)  BI  = M_L_DQ<23>
  178  VSS(32)  GROUND  = GND
  179  DQ(19)  BI  = M_L_DQ<19>
  180  VSS(31)  GROUND  = GND
  181  DQ(29)  BI  = M_L_DQ<29>
  182  VSS(30)  GROUND  = GND
  183  DQ(25)  BI  = M_L_DQ<25>
  184  VSS(29)  GROUND  = GND
  185  DQS3N  BI  = M_L_DQS_DN<3>
  186  DQS3P  BI  = M_L_DQS_DP<3>
  187  VSS(28)  GROUND  = GND
  188  DQ(31)  BI  = M_L_DQ<31>
  189  VSS(27)  GROUND  = GND
  190  DQ(27)  BI  = M_L_DQ<27>
  191  VSS(26)  GROUND  = GND
  192  CB(5)  BI  = M_L_ECC<5>
  193  VSS(25)  GROUND  = GND
  194  CB(1)  BI  = M_L_ECC<1>
  195  VSS(24)  GROUND  = GND
  196  DQS8N  BI  = M_L_DQS_DN<8>
  197  DQS8P  BI  = M_L_DQS_DP<8>
  198  VSS(23)  GROUND  = GND
  199  CB(7)  BI  = M_L_ECC<7>
  200  VSS(22)  GROUND  = GND
  201  CB(3)  BI  = M_L_ECC<3>
  202  VSS(21)  GROUND  = GND
  203  CKE(1)  BI  = M_L_CKE<3>
  204  VDD(12)  POWER  = PVDDQ_KLM
  205  RFU(0)  BI  = TP_CH_L_DIMM0_RFU_0
  206  VDD(11)  POWER  = PVDDQ_KLM
  207  BG(1)  BI  = M_L_BG<1>
  208  ALERT_N  BI  = M_L_ALERT_N
  209  VDD(10)  POWER  = PVDDQ_KLM
  210  A11  BI  = M_L_MA<11>
  211  A7  BI  = M_L_MA<7>
  212  VDD(9)  POWER  = PVDDQ_KLM
  213  A5  BI  = M_L_MA<5>
  214  A4  BI  = M_L_MA<4>
  215  VDD(8)  POWER  = PVDDQ_KLM
  216  A2  BI  = M_L_MA<2>
  217  VDD(7)  POWER  = PVDDQ_KLM
  218  CK1P  BI  = M_L_CLK_DP<3>
  219  CK1N  BI  = M_L_CLK_DN<3>
  220  VDD(6)  POWER  = PVDDQ_KLM
  221  VTT(0)  POWER  = PVTT_KLM
  222  PAR  BI  = M_L_PAR
  223  VDD(5)  POWER  = PVDDQ_KLM
  224  BA(1)  BI  = M_L_BA<1>
  225  A10  BI  = M_L_MA<10>
  226  VDD(4)  POWER  = PVDDQ_KLM
  227  RFU(1)  BI  = TP_CH_L_DIMM0_RFU_1
  228  A14_WE_N  BI  = M_L_MA<14>
  229  VDD(3)  POWER  = PVDDQ_KLM
  230  SAVE_N_NC  BI  = FM_ADR_COMPLETE_KLM_N
  231  VDD(2)  POWER  = PVDDQ_KLM
  232  A13  BI  = M_L_MA<13>
  233  VDD(1)  POWER  = PVDDQ_KLM
  234  A17  BI  = M_L_MA<17>
  235  C(2)  BI  = M_L_C<2>
  236  VDD(0)  POWER  = PVDDQ_KLM
  237  S3_N_C(1)  BI  = M_L_CS_N<7>
  238  SA(2)  BI  = GND
  239  VSS(20)  GROUND  = GND
  240  DQ(37)  BI  = M_L_DQ<37>
  241  VSS(19)  GROUND  = GND
  242  DQ(33)  BI  = M_L_DQ<33>
  243  VSS(18)  GROUND  = GND
  244  DQS4N  BI  = M_L_DQS_DN<4>
  245  DQS4P  BI  = M_L_DQS_DP<4>
  246  VSS(17)  GROUND  = GND
  247  DQ(39)  BI  = M_L_DQ<39>
  248  VSS(16)  GROUND  = GND
  249  DQ(35)  BI  = M_L_DQ<35>
  250  VSS(15)  GROUND  = GND
  251  DQ(45)  BI  = M_L_DQ<45>
  252  VSS(14)  GROUND  = GND
  253  DQ(41)  BI  = M_L_DQ<41>
  254  VSS(13)  GROUND  = GND
  255  DQS5N  BI  = M_L_DQS_DN<5>
  256  DQS5P  BI  = M_L_DQS_DP<5>
  257  VSS(12)  GROUND  = GND
  258  DQ(47)  BI  = M_L_DQ<47>
  259  VSS(11)  GROUND  = GND
  260  DQ(43)  BI  = M_L_DQ<43>
  261  VSS(10)  GROUND  = GND
  262  DQ(53)  BI  = M_L_DQ<53>
  263  VSS(9)  GROUND  = GND
  264  DQ(49)  BI  = M_L_DQ<49>
  265  VSS(8)  GROUND  = GND
  266  DQS6N  BI  = M_L_DQS_DN<6>
  267  DQS6P  BI  = M_L_DQS_DP<6>
  268  VSS(7)  GROUND  = GND
  269  DQ(55)  BI  = M_L_DQ<55>
  270  VSS(6)  GROUND  = GND
  271  DQ(51)  BI  = M_L_DQ<51>
  272  VSS(5)  GROUND  = GND
  273  DQ(61)  BI  = M_L_DQ<61>
  274  VSS(4)  GROUND  = GND
  275  DQ(57)  BI  = M_L_DQ<57>
  276  VSS(3)  GROUND  = GND
  277  DQS7N  BI  = M_L_DQS_DN<7>
  278  DQS7P  BI  = M_L_DQS_DP<7>
  279  VSS(2)  GROUND  = GND
  280  DQ(63)  BI  = M_L_DQ<63>
  281  VSS(1)  GROUND  = GND
  282  DQ(59)  BI  = M_L_DQ<59>
  283  VSS(0)  GROUND  = GND
  284  VDDSPD  BI  = PVPP_KLM
  285  SDA  BI  = SMB_DDR_KLM_VPP_SDA
  286  VPP(1)  POWER  = PVPP_KLM
  287  VPP(0)  POWER  = PVPP_KLM
  288  VPP(2)  POWER  = PVPP_KLM
